FILE_TYPE = CONNECTIVITY;
{Allegro Design Entry HDL 17.2-2016 S081 (4005846) 1/11/2022}
"PAGE_NUMBER" = 51;
0"NC";
1"P3V3_LDO\g";
2"P12V_AUX\g";
3"P12V_AUX\g";
4"P5V_AUX_VCC\g";
5"P5V_AUX\g";
6"P12V_AUX\g";
7"GND\g";
8"GND\g";
9"GND\g";
10"GND\g";
11"GND\g";
12"GND\g";
13"GND\g";
14"GND\g";
15"GND\g";
16"GND\g";
17"GND\g";
18"GND\g";
19"GND\g";
20"GND\g";
21"GND\g";
22"GND\g";
23"SW_P5V_AUX_FLT";
24"EN_P5V_AUX";
25"U56_ADJ_1";
26"P5V_AUX_FB";
27"SW_P5V_AUX_BST";
28"SW_P5V_AUX_SW";
29"EN_P3V3_R1";
30"PWRGD_P5V_AUX";
31"PWRGD_P5V_AUX_R";
32"P5V_AUX_REF";
33"P5V_AUX_CS";
34"P5V_AUX_VCC";
%"Q_CAP"
"1","(-2525,500)","0","pure_quanta","I1";
;
VALUE"0.1UF"
TOLERANCE"10%"
PACK_TYPE"0402"
VOLTAGE"25V"
PART_NUMBER"CH4104K1B00"
MATERIAL"X7R"
CDS_LIB"pure_quanta"
SEC_TYPE"0402"
LOCATION"PC205"
SEC"1";
"B"
$PN"2"12;
"A"
$PN"1"24;
%"UNIVERSAL_GND"
"1","(-1225,300)","0","logical_power","I10";
;
HDL_POWER"GND"
CDS_LIB"logical_power";
"A"13;
%"UNIVERSAL_GND"
"1","(-650,-275)","0","logical_power","I12";
;
HDL_POWER"GND"
CDS_LIB"logical_power";
"A"14;
%"Q_CAP"
"1","(-650,25)","0","pure_quanta","I13";
;
MATERIAL"X6S"
VOLTAGE"25V"
TOLERANCE"10%"
VALUE"1UF"
PACK_TYPE"C0402"
PART_NUMBER"CH5104KEB02"
CDS_LIB"pure_quanta"
SEC_TYPE"C0402"
LOCATION"PC208"
SEC"1";
"B"
$PN"2"14;
"A"
$PN"1"34;
%"UNIVERSAL_GND"
"1","(-1025,1075)","0","logical_power","I14";
;
HDL_POWER"GND"
CDS_LIB"logical_power";
"A"15;
%"UNIVERSAL_GND"
"1","(1475,-425)","0","logical_power","I19";
;
HDL_POWER"GND"
CDS_LIB"logical_power";
"A"19;
%"UNIVERSAL_GND"
"1","(-2075,100)","0","logical_power","I2";
;
HDL_POWER"GND"
CDS_LIB"logical_power";
"A"12;
%"UNIVERSAL_GND"
"1","(1750,-700)","0","logical_power","I20";
;
HDL_POWER"GND"
CDS_LIB"logical_power";
"A"17;
%"Q_RES"
"2","(2825,1450)","0","pure_quanta","I21";
;
WATTAGE"1/16W"
MATERIAL"CHIP"
PART_NUMBER"CS31002FB08"
PACK_TYPE"0402LF"
VALUE"10K"
TOLERANCE"1%"
SEC_TYPE"0402LF"
CDS_LIB"pure_quanta"
LOCATION"PR241"
SEC"1";
"A"
$PN"1"4;
"B"
$PN"2"31;
%"Q_CAP"
"1","(1750,-275)","0","pure_quanta","I22";
;
PACK_TYPE"0402"
PART_NUMBER"CH4104K1B00"
VALUE"0.1UF"
VOLTAGE"25V"
MATERIAL"X7R"
TOLERANCE"10%"
CDS_LIB"pure_quanta"
LOCATION"PC271"
$SEC"1"
CDS_SEC"1";
"B"
$PN"2"17;
"A"
$PN"1"32;
%"Q_CAP"
"1","(1975,825)","0","pure_quanta","I23";
;
VOLTAGE"16V"
VALUE"0.22UF"
MATERIAL"X7R"
TOLERANCE"10%"
PART_NUMBER"CH4223K1B00"
PACK_TYPE"0402"
SEC_TYPE"0402"
CDS_LIB"pure_quanta"
LOCATION"PC216"
SEC"1";
"B"
$PN"2"28;
"A"
$PN"1"27;
%"VCCAUX15"
"1","(2825,1725)","0","logical_power","I24";
;
HDL_POWER"P5V_AUX_VCC"
CDS_LIB"logical_power";
"A"4;
%"UNIVERSAL_GND"
"1","(2850,-600)","0","logical_power","I25";
;
HDL_POWER"GND"
CDS_LIB"logical_power";
"A"18;
%"Q_RES"
"2","(2850,-325)","0","pure_quanta","I26";
;
PACK_TYPE"0402LF"
PART_NUMBER"CS31242FB02"
MATERIAL"CHIP"
WATTAGE"1/16W"
TOLERANCE"1%"
VALUE"12.4K"
CDS_LIB"pure_quanta"
LOCATION"PR526"
$SEC"1"
CDS_SEC"1";
"A"
$PN"1"26;
"B"
$PN"2"18;
%"Q_CAP"
"2","(4100,-500)","0","pure_quanta","I27";
;
PART_NUMBER"CH06806JB01"
TOLERANCE"5%"
MATERIAL"COG"
VOLTAGE"50V"
PACK_TYPE"C0402"
VALUE"68PF"
CDS_LIB"pure_quanta"
LOCATION"PC272"
$SEC"1"
CDS_SEC"1";
"A"
$PN"1"26;
"B"
$PN"2"5;
%"Q_INDUCTOR"
"1","(3250,700)","0","pure_quanta","I28";
;
PART_NUMBER"CV-47A0MZ10"
VALUE"4.7UH"
MATERIAL"IND"
R1"DCR=13.2MOHM"
PACK_TYPE"SMLF"
R3"ISAT=13A"
CDS_LIB"pure_quanta"
NEEDS_NO_SIZE"TRUE"
LOCATION"PL34"
$SEC"1"
CDS_SEC"1";
"1"
$PN"1"28;
"2"
$PN"2"5;
%"Q_RES"
"2","(-2075,500)","0","pure_quanta","I3";
;
VALUE"100K"
PACK_TYPE"0402LF"
MATERIAL"CHIP"
WATTAGE"1/16W"
TOLERANCE"1%"
PART_NUMBER"CS41002FB09"
CDS_LIB"pure_quanta"
LOCATION"PR522"
$SEC"1"
CDS_SEC"1";
"A"
$PN"1"24;
"B"
$PN"2"12;
%"Q_RES"
"1","(4100,-150)","0","pure_quanta","I30";
;
VALUE"91K"
TOLERANCE"1%"
PART_NUMBER"CS39102FB06"
PACK_TYPE"0402LF"
MATERIAL"CHIP"
WATTAGE"1/16W"
CDS_LIB"pure_quanta"
LOCATION"PR527"
$SEC"1"
CDS_SEC"1";
"B"
$PN"2"5;
"A"
$PN"1"26;
%"Q_CAP"
"1","(3725,425)","0","pure_quanta","I31";
;
PACK_TYPE"0402"
PART_NUMBER"CH4104K1B00"
VALUE"0.1UF"
VOLTAGE"25V"
TOLERANCE"10%"
MATERIAL"X7R"
SEC_TYPE"0402"
CDS_LIB"pure_quanta"
LOCATION"PC212"
SEC"1";
"B"
$PN"2"22;
"A"
$PN"1"5;
%"Q_CAP"
"1","(4150,425)","0","pure_quanta","I32";
;
VALUE"22UF"
VOLTAGE"10V"
PART_NUMBER"CH6222MEA00"
PACK_TYPE"C0805"
TOLERANCE"20%"
MATERIAL"X6S"
CDS_LIB"pure_quanta"
LOCATION"PC213"
$SEC"1"
CDS_SEC"1";
"B"
$PN"2"22;
"A"
$PN"1"5;
%"Q_CAP"
"1","(4500,425)","0","pure_quanta","I33";
;
VALUE"22UF"
VOLTAGE"10V"
TOLERANCE"20%"
MATERIAL"X6S"
PART_NUMBER"CH6222MEA00"
PACK_TYPE"C0805"
CDS_LIB"pure_quanta"
LOCATION"PC214"
$SEC"1"
CDS_SEC"1";
"B"
$PN"2"22;
"A"
$PN"1"5;
%"UNIVERSAL_GND"
"1","(5025,100)","0","logical_power","I35";
;
HDL_POWER"GND"
CDS_LIB"logical_power";
"A"22;
%"Q_CAP"
"1","(4825,425)","0","pure_quanta","I36";
;
PACK_TYPE"C0805"
PART_NUMBER"CH6222MEA00"
VALUE"22UF"
TOLERANCE"20%"
MATERIAL"X6S"
VOLTAGE"10V"
CDS_LIB"pure_quanta"
LOCATION"PC215"
$SEC"1"
CDS_SEC"1";
"B"
$PN"2"22;
"A"
$PN"1"5;
%"Q_CAP"
"1","(5175,425)","0","pure_quanta","I37";
;
VALUE"22UF"
PACK_TYPE"C0805"
PART_NUMBER"CH6222MEA00"
TOLERANCE"20%"
MATERIAL"X6S"
VOLTAGE"10V"
CDS_LIB"pure_quanta"
LOCATION"PC217"
$SEC"1"
CDS_SEC"1";
"B"
$PN"2"22;
"A"
$PN"1"5;
%"VCCAUX15"
"1","(5675,800)","0","logical_power","I38";
;
HDL_POWER"P5V_AUX"
CDS_LIB"logical_power";
"A"5;
%"Q_INDUCTOR"
"1","(-1775,1675)","0","pure_quanta","I39";
;
PART_NUMBER"CX220TN1001"
PACK_TYPE"SMLF"
MATERIAL"IND"
VALUE"BLM18SN220TN1D/8000MA"
NEEDS_NO_SIZE"TRUE"
CDS_LIB"pure_quanta"
LOCATION"PL4"
$SEC"1"
CDS_SEC"1";
"1"
$PN"1"3;
"2"
$PN"2"23;
%"Q_RES"
"2","(-2325,900)","0","pure_quanta","I4";
;
PACK_TYPE"0402LF"
PART_NUMBER"CS46812FB06"
MATERIAL"CHIP"
WATTAGE"1/16W"
TOLERANCE"1%"
VALUE"681K"
CDS_LIB"pure_quanta"
LOCATION"PR521"
$SEC"1"
CDS_SEC"1";
"A"
$PN"1"2;
"B"
$PN"2"24;
%"MPQ8633AGLEC807Z"
"1","(925,500)","0","pure_quanta","I42";
;
PART_TYPE"SMLF"
MATERIAL"IC"
PART_NUMBER"AL008633007"
VALUE"MPQ8633AGLE-C807-Z"
CDS_LMAN_SYM_OUTLINE"-250,725,250,-725"
NEEDS_NO_SIZE"TRUE"
CDS_LIB"pure_quanta"
LOCATION"PU38"
$SEC"1"
CDS_SEC"1";
"VIN2"
$PN"21"23;
"CS"
$PN"3"33;
"MODE"
$PN"4"13;
"TRK_REF"
$PN"5"32;
"SW"
$PN"20"28;
"RGND"
$PN"6"17;
"VCC"
$PN"19"34;
"AGND"
$PN"2"19;
"FB"
$PN"7"26;
"BST"
$PN"1"27;
"EN"
$PN"8"24;
"PGND"
$PN"11_18"19;
"PGOOD"
$PN"9"31;
"VIN1"
$PN"10"23;
%"Q_RES"
"2","(2400,1000)","0","pure_quanta","I43";
;
PACK_TYPE"0402LF"
VALUE"100K"
TOLERANCE"1%"
WATTAGE"1/16W"
MATERIAL"EMPTY"
PART_NUMBER"CS41002FB09"
CDS_LIB"pure_quanta"
LOCATION"PR245"
$SEC"1"
CDS_SEC"1";
"A"
$PN"1"31;
"B"
$PN"2"20;
%"UNIVERSAL_GND"
"1","(2400,775)","0","logical_power","I44";
;
HDL_POWER"GND"
CDS_LIB"logical_power";
"A"20;
%"Q_CAP"
"1","(-350,1400)","0","pure_quanta","I45";
;
VALUE"0.1UF"
VOLTAGE"25V"
TOLERANCE"10%"
MATERIAL"X7R"
PART_NUMBER"CH4104K1B00"
PACK_TYPE"0402"
SEC_TYPE"0402"
CDS_LIB"pure_quanta"
LOCATION"PC210"
SEC"1";
"B"
$PN"2"15;
"A"
$PN"1"23;
%"Q_CAP"
"1","(-1025,1400)","0","pure_quanta","I47";
;
VALUE"22UF"
TOLERANCE"20%"
VOLTAGE"16V"
MATERIAL"X6S"
PACK_TYPE"C0805"
PART_NUMBER"CH6223MEA01"
SEC_TYPE"C0805"
CDS_LIB"pure_quanta"
LOCATION"PC206"
SEC"1";
"B"
$PN"2"15;
"A"
$PN"1"23;
%"Q_CAP"
"1","(-650,1400)","0","pure_quanta","I48";
;
VOLTAGE"16V"
VALUE"22UF"
TOLERANCE"20%"
MATERIAL"X6S"
PART_NUMBER"CH6223MEA01"
PACK_TYPE"C0805"
SEC_TYPE"C0805"
CDS_LIB"pure_quanta"
LOCATION"PC207"
SEC"1";
"B"
$PN"2"15;
"A"
$PN"1"23;
%"Q_CAP"
"1","(3550,975)","0","pure_quanta","I49";
;
VALUE"0.001UF"
VOLTAGE"50V"
PACK_TYPE"C0402"
PART_NUMBER"CH30106KB19"
MATERIAL"EMPTY"
TOLERANCE"10%"
CDS_LIB"pure_quanta"
LOCATION"C150"
$SEC"1"
CDS_SEC"1";
"B"
$PN"2"21;
"A"
$PN"1"31;
%"VCCAUX15"
"1","(-2325,1075)","0","logical_power","I5";
;
HDL_POWER"P12V_AUX"
CDS_LIB"logical_power";
"A"2;
%"UNIVERSAL_GND"
"1","(3550,775)","0","logical_power","I50";
;
HDL_POWER"GND"
CDS_LIB"logical_power";
"A"21;
%"Q_RES"
"1","(4275,1175)","0","pure_quanta","I51";
;
TOLERANCE"5%"
MATERIAL"CHIP"
PACK_TYPE"0402LF"
PART_NUMBER"CS00002JB13"
VALUE"0"
WATTAGE"1/16W"
CDS_LIB"pure_quanta"
LOCATION"R292"
$SEC"1"
CDS_SEC"1";
"B"
$PN"2"30;
"A"
$PN"1"31;
%"Q_CAP"
"1","(-2275,1475)","0","pure_quanta","I52";
;
TOLERANCE"10%"
VOLTAGE"25V"
PACK_TYPE"0402"
VALUE"0.1UF"
MATERIAL"X7R"
PART_NUMBER"CH4104K1B00"
CDS_LIB"pure_quanta"
$LOCATION"C241"
CDS_LOCATION"C241"
$SEC"1"
CDS_SEC"1";
"B"
$PN"2"11;
"A"
$PN"1"3;
%"UNIVERSAL_GND"
"1","(-2275,1275)","0","logical_power","I53";
;
CDS_LIB"logical_power"
HDL_POWER"GND";
"A"11;
%"Q_RES"
"1","(4275,1675)","0","pure_quanta","I54";
;
VALUE"0"
PART_NUMBER"CS00002JB13"
TOLERANCE"5%"
WATTAGE"1/16W"
PACK_TYPE"0402LF"
MATERIAL"EMPTY"
CDS_LIB"pure_quanta"
$LOCATION"R868"
CDS_LOCATION"R868"
$SEC"1"
CDS_SEC"1";
"B"
$PN"2"29;
"A"
$PN"1"31;
%"AP2205W57"
"1","(-425,3500)","0","pure_quanta","I56";
;
MATERIAL"IC"
PART_NUMBER"AL002205001"
PART_TYPE"SMLF"
VALUE"AP2205-W5-7"
CDS_LIB"pure_quanta"
NEEDS_NO_SIZE"TRUE"
CDS_LMAN_SYM_OUTLINE"-200,200,150,-200"
$LOCATION"U56"
CDS_LOCATION"U56"
$SEC"1"
CDS_SEC"1";
"EN"
$PN"3"6;
"GND"
$PN"2"10;
"VIN"
$PN"1"6;
"ADJ||NC"
$PN"4"25;
"VOUT"
$PN"5"1;
%"Q_RES"
"2","(325,3200)","0","pure_quanta","I57";
;
TOLERANCE"1%"
WATTAGE"1/16W"
PART_NUMBER"CS31002FB08"
MATERIAL"CHIP"
PACK_TYPE"0402LF"
VALUE"10K"
CDS_LIB"pure_quanta"
$LOCATION"R677"
CDS_LOCATION"R677"
$SEC"1"
CDS_SEC"1";
"A"
$PN"1"25;
"B"
$PN"2"7;
%"UNIVERSAL_GND"
"1","(-875,3300)","0","logical_power","I58";
;
HDL_POWER"GND"
CDS_LIB"logical_power";
"A"10;
%"UNIVERSAL_POWER"
"1","(-1125,3975)","0","logical_power","I59";
;
HDL_POWER"P12V_AUX"
CDS_LIB"logical_power";
"A"6;
%"VCCAUX15"
"1","(-2275,2000)","0","logical_power","I6";
;
HDL_POWER"P12V_AUX"
CDS_LIB"logical_power";
"A"3;
%"Q_CAP"
"1","(-1125,3525)","0","pure_quanta","I60";
;
PART_NUMBER"CH5104KEB02"
MATERIAL"X6S"
TOLERANCE"10%"
VOLTAGE"25V"
VALUE"1UF"
PACK_TYPE"C0402"
CDS_LIB"pure_quanta"
$LOCATION"C226"
CDS_LOCATION"C226"
$SEC"1"
CDS_SEC"1";
"B"
$PN"2"9;
"A"
$PN"1"6;
%"UNIVERSAL_GND"
"1","(-1125,3300)","0","logical_power","I61";
;
CDS_LIB"logical_power"
HDL_POWER"GND";
"A"9;
%"Q_RES"
"2","(325,3600)","0","pure_quanta","I62";
;
PACK_TYPE"0402LF"
PART_NUMBER"CS31692FB03"
VALUE"16.9K"
TOLERANCE"1%"
WATTAGE"1/16W"
MATERIAL"CHIP"
CDS_LIB"pure_quanta"
$LOCATION"R631"
CDS_LOCATION"R631"
$SEC"1"
CDS_SEC"1";
"A"
$PN"1"1;
"B"
$PN"2"25;
%"UNIVERSAL_GND"
"1","(325,3000)","0","logical_power","I63";
;
CDS_LIB"logical_power"
HDL_POWER"GND";
"A"7;
%"UNIVERSAL_GND"
"1","(850,3325)","0","logical_power","I65";
;
CDS_LIB"logical_power"
HDL_POWER"GND";
"A"8;
%"UNIVERSAL_POWER"
"1","(850,4000)","0","logical_power","I66";
;
HDL_POWER"P3V3_LDO"
CDS_LIB"logical_power";
"A"1;
%"Q_CAP"
"1","(850,3525)","0","pure_quanta","I68";
;
VALUE"2.2UF"
VOLTAGE"10V"
TOLERANCE"10%"
MATERIAL"X6S"
PART_NUMBER"CH5222KEB01"
PACK_TYPE"C0402"
CDS_LIB"pure_quanta"
LOCATION"C227"
$SEC"1"
CDS_SEC"1";
"B"
$PN"2"8;
"A"
$PN"1"1;
%"UNIVERSAL_GND"
"1","(-25,-725)","0","logical_power","I8";
;
HDL_POWER"GND"
CDS_LIB"logical_power";
"A"16;
%"Q_RES"
"2","(-25,-450)","0","pure_quanta","I9";
;
MATERIAL"CHIP"
WATTAGE"1/16W"
TOLERANCE"1%"
VALUE"20.5K"
PART_NUMBER"CS32052FB02"
PACK_TYPE"0402LF"
SEC_TYPE"0402LF"
CDS_LIB"pure_quanta"
LOCATION"PR525"
SEC"1";
"A"
$PN"1"33;
"B"
$PN"2"16;
END.
